# T6G (Grand Teton) — schematic netlist excerpt (pin names and nets, part order shuffled) for the footprints in the layout excerpt that follows; sources: Cadence DE-HDL packaged netlist, KiCad conversion of 04192023_DAF0TMB3IC0_F0TG_MB_C_brd_V02_OCP.brd

PC20  Q_CAP  1UF 25V 10% X6S  pkg C0402  page 226 : A = PVDD18_S5_P1_VCC ; B = GND
C68  Q_CAP  0.1UF 25V 10% X7R  pkg 0402  page 183 : A = P3V3_9ZXL045_P1_VDDA ; B = GND

(kicad_pcb
	(version 20260206)
	(generator "pcbnew")
	(generator_version "10.0")
	(general
		(thickness 1.6)
		(legacy_teardrops no)
	)
	(paper "A4")
	(title_block
		(title "04192023_DAF0TMB3IC0_F0TG_MB_C_brd_V02_OCP.brd")
		(comment 1 "Grand Teton / footprints 3814-3815 of 8354")
	)
	(layers
		(0 "F.Cu" signal "TOP")
		(4 "In1.Cu" signal "GND")
		(6 "In2.Cu" signal "IN1")
		(8 "In3.Cu" signal "GND1")
		(10 "In4.Cu" signal "IN2")
		(12 "In5.Cu" signal "GND2")
		(14 "In6.Cu" signal "IN3")
		(16 "In7.Cu" signal "GND3")
		(18 "In8.Cu" signal "VCC")
		(20 "In9.Cu" signal "VCC1")
		(22 "In10.Cu" signal "GND4")
		(24 "In11.Cu" signal "IN4")
		(26 "In12.Cu" signal "GND5")
		(28 "In13.Cu" signal "IN5")
		(30 "In14.Cu" signal "GND6")
		(32 "In15.Cu" signal "IN6")
		(34 "In16.Cu" signal "GND7")
		(2 "B.Cu" signal "BOTTOM")
		(9 "F.Adhes" user "F.Adhesive")
		(11 "B.Adhes" user "B.Adhesive")
		(13 "F.Paste" user "Package Geometry/Pastemask Top")
		(15 "B.Paste" user "Package Geometry/Pastemask Bottom")
		(5 "F.SilkS" user "Ref Des/Silkscreen Top")
		(7 "B.SilkS" user "Ref Des/Silkscreen Bottom")
		(1 "F.Mask" user "Board Geometry/Soldermask Top")
		(3 "B.Mask" user "Board Geometry/Soldermask Bottom")
		(17 "Dwgs.User" user "User.Drawings")
		(19 "Cmts.User" user "User.Comments")
		(21 "Eco1.User" user "User.Eco1")
		(23 "Eco2.User" user "User.Eco2")
		(25 "Edge.Cuts" user "Board Geometry/Outline")
		(27 "Margin" user)
		(31 "F.CrtYd" user "Package Geometry/Place Bound Top")
		(29 "B.CrtYd" user "Package Geometry/Place Bound Bottom")
		(35 "F.Fab" user "Ref Des/Assembly Top")
		(33 "B.Fab" user "Ref Des/Assembly Bottom")
	)
	(footprint ""
		(layer "F.Cu")
		(at 68.432426 -155.237688)
		(property "Reference" "PC20"
			(at 0 0 0)
			(layer "F.SilkS")
			(hide yes)
			(effects
				(font
					(size 1.27 1.27)
				)
			)
		)
		(property "Value" ""
			(at 0 0 0)
			(layer "F.Fab")
			(effects
				(font
					(size 1.27 1.27)
				)
			)
		)
		(duplicate_pad_numbers_are_jumpers no)
		(fp_line
			(start -0.7874 -0.4064)
			(end 0.7874 -0.4064)
			(stroke
				(width 0.1524)
				(type default)
			)
			(layer "F.SilkS")
		)
		(fp_line
			(start -0.7874 0.4064)
			(end -0.7874 -0.4064)
			(stroke
				(width 0.1524)
				(type default)
			)
			(layer "F.SilkS")
		)
		(fp_line
			(start 0.7874 -0.4064)
			(end 0.7874 0.4064)
			(stroke
				(width 0.1524)
				(type default)
			)
			(layer "F.SilkS")
		)
		(fp_line
			(start 0.7874 0.4064)
			(end -0.7874 0.4064)
			(stroke
				(width 0.1524)
				(type default)
			)
			(layer "F.SilkS")
		)
		(fp_line
			(start -0.67945 -0.305054)
			(end -0.12065 -0.305054)
			(stroke
				(width 0.1)
				(type default)
			)
			(layer "F.Fab")
		)
		(fp_line
			(start -0.67945 0.3048)
			(end -0.67945 -0.305054)
			(stroke
				(width 0.1)
				(type default)
			)
			(layer "F.Fab")
		)
		(fp_line
			(start -0.12065 -0.305054)
			(end -0.12065 -0.2794)
			(stroke
				(width 0.1)
				(type default)
			)
			(layer "F.Fab")
		)
		(fp_line
			(start -0.12065 -0.2794)
			(end 0.12065 -0.2794)
			(stroke
				(width 0.1)
				(type default)
			)
			(layer "F.Fab")
		)
		(fp_line
			(start -0.12065 0.2794)
			(end -0.12065 0.3048)
			(stroke
				(width 0.1)
				(type default)
			)
			(layer "F.Fab")
		)
		(fp_line
			(start -0.12065 0.3048)
			(end -0.67945 0.3048)
			(stroke
				(width 0.1)
				(type default)
			)
			(layer "F.Fab")
		)
		(fp_line
			(start 0.120396 0.2794)
			(end -0.12065 0.2794)
			(stroke
				(width 0.1)
				(type default)
			)
			(layer "F.Fab")
		)
		(fp_line
			(start 0.120396 0.3048)
			(end 0.120396 0.2794)
			(stroke
				(width 0.1)
				(type default)
			)
			(layer "F.Fab")
		)
		(fp_line
			(start 0.12065 -0.3048)
			(end 0.67945 -0.3048)
			(stroke
				(width 0.1)
				(type default)
			)
			(layer "F.Fab")
		)
		(fp_line
			(start 0.12065 -0.2794)
			(end 0.12065 -0.3048)
			(stroke
				(width 0.1)
				(type default)
			)
			(layer "F.Fab")
		)
		(fp_line
			(start 0.67945 -0.3048)
			(end 0.67945 0.3048)
			(stroke
				(width 0.1)
				(type default)
			)
			(layer "F.Fab")
		)
		(fp_line
			(start 0.67945 0.3048)
			(end 0.120396 0.3048)
			(stroke
				(width 0.1)
				(type default)
			)
			(layer "F.Fab")
		)
		(pad "1" smd circle
			(at -0.40005 0)
			(size 0 0)
			(layers "F.Cu" "F.Mask" "F.Paste")
			(net "PVDD18_S5_P1_VCC")
		)
		(pad "2" smd circle
			(at 0.40005 0)
			(size 0 0)
			(layers "F.Cu" "F.Mask" "F.Paste")
			(net "GND")
		)
	)
	(footprint ""
		(layer "F.Cu")
		(at 112.649 -411.1498)
		(property "Reference" "C68"
			(at 0 0 0)
			(layer "F.SilkS")
			(hide yes)
			(effects
				(font
					(size 1.27 1.27)
				)
			)
		)
		(property "Value" ""
			(at 0 0 0)
			(layer "F.Fab")
			(effects
				(font
					(size 1.27 1.27)
				)
			)
		)
		(duplicate_pad_numbers_are_jumpers no)
		(fp_line
			(start -0.7874 -0.4064)
			(end 0.7874 -0.4064)
			(stroke
				(width 0.1524)
				(type default)
			)
			(layer "F.SilkS")
		)
		(fp_line
			(start -0.7874 0.4064)
			(end -0.7874 -0.4064)
			(stroke
				(width 0.1524)
				(type default)
			)
			(layer "F.SilkS")
		)
		(fp_line
			(start 0.7874 -0.4064)
			(end 0.7874 0.4064)
			(stroke
				(width 0.1524)
				(type default)
			)
			(layer "F.SilkS")
		)
		(fp_line
			(start 0.7874 0.4064)
			(end -0.7874 0.4064)
			(stroke
				(width 0.1524)
				(type default)
			)
			(layer "F.SilkS")
		)
		(fp_line
			(start -0.67945 -0.305054)
			(end -0.12065 -0.305054)
			(stroke
				(width 0.1)
				(type default)
			)
			(layer "F.Fab")
		)
		(fp_line
			(start -0.67945 0.3048)
			(end -0.67945 -0.305054)
			(stroke
				(width 0.1)
				(type default)
			)
			(layer "F.Fab")
		)
		(fp_line
			(start -0.12065 -0.305054)
			(end -0.12065 -0.2794)
			(stroke
				(width 0.1)
				(type default)
			)
			(layer "F.Fab")
		)
		(fp_line
			(start -0.12065 -0.2794)
			(end 0.12065 -0.2794)
			(stroke
				(width 0.1)
				(type default)
			)
			(layer "F.Fab")
		)
		(fp_line
			(start -0.12065 0.2794)
			(end -0.12065 0.3048)
			(stroke
				(width 0.1)
				(type default)
			)
			(layer "F.Fab")
		)
		(fp_line
			(start -0.12065 0.3048)
			(end -0.67945 0.3048)
			(stroke
				(width 0.1)
				(type default)
			)
			(layer "F.Fab")
		)
		(fp_line
			(start 0.120396 0.2794)
			(end -0.12065 0.2794)
			(stroke
				(width 0.1)
				(type default)
			)
			(layer "F.Fab")
		)
		(fp_line
			(start 0.120396 0.3048)
			(end 0.120396 0.2794)
			(stroke
				(width 0.1)
				(type default)
			)
			(layer "F.Fab")
		)
		(fp_line
			(start 0.12065 -0.3048)
			(end 0.67945 -0.3048)
			(stroke
				(width 0.1)
				(type default)
			)
			(layer "F.Fab")
		)
		(fp_line
			(start 0.12065 -0.2794)
			(end 0.12065 -0.3048)
			(stroke
				(width 0.1)
				(type default)
			)
			(layer "F.Fab")
		)
		(fp_line
			(start 0.67945 -0.3048)
			(end 0.67945 0.3048)
			(stroke
				(width 0.1)
				(type default)
			)
			(layer "F.Fab")
		)
		(fp_line
			(start 0.67945 0.3048)
			(end 0.120396 0.3048)
			(stroke
				(width 0.1)
				(type default)
			)
			(layer "F.Fab")
		)
		(pad "1" smd circle
			(at -0.40005 0)
			(size 0 0)
			(layers "F.Cu" "F.Mask" "F.Paste")
			(net "P3V3_9ZXL045_P1_VDDA")
		)
		(pad "2" smd circle
			(at 0.40005 0)
			(size 0 0)
			(layers "F.Cu" "F.Mask" "F.Paste")
			(net "GND")
		)
	)
)
